(kicad_pcb
	(version 20260206)
	(generator "pcbnew")
	(generator_version "10.0")
	(general
		(thickness 1.6)
		(legacy_teardrops no)
	)
	(paper "A4")
	(title_block
		(title "Wiwynn_Tioga_Pass_MB.brd")
		(comment 1 "Tioga Pass / footprints 384-391 of 4770")
	)
	(layers
		(0 "F.Cu" signal "TOP")
		(4 "In1.Cu" signal "L2GND")
		(6 "In2.Cu" signal "L3")
		(8 "In3.Cu" signal "L4GND")
		(10 "In4.Cu" signal "L5")
		(12 "In5.Cu" signal "L6GND")
		(14 "In6.Cu" signal "L7VCC")
		(16 "In7.Cu" signal "L8VCC")
		(18 "In8.Cu" signal "L9GND")
		(20 "In9.Cu" signal "L10")
		(22 "In10.Cu" signal "L11GND")
		(24 "In11.Cu" signal "L12")
		(26 "In12.Cu" signal "L13GND")
		(2 "B.Cu" signal "BOTTOM")
		(9 "F.Adhes" user "F.Adhesive")
		(11 "B.Adhes" user "B.Adhesive")
		(13 "F.Paste" user "Package Geometry/Pastemask Top")
		(15 "B.Paste" user "Package Geometry/Pastemask Bottom")
		(5 "F.SilkS" user "Ref Des/Silkscreen Top")
		(7 "B.SilkS" user "Ref Des/Silkscreen Bottom")
		(1 "F.Mask" user "Board Geometry/Soldermask Top")
		(3 "B.Mask" user "Board Geometry/Soldermask Bottom")
		(17 "Dwgs.User" user "User.Drawings")
		(19 "Cmts.User" user "User.Comments")
		(21 "Eco1.User" user "User.Eco1")
		(23 "Eco2.User" user "User.Eco2")
		(25 "Edge.Cuts" user "Board Geometry/Outline")
		(27 "Margin" user)
		(31 "F.CrtYd" user "Package Geometry/Place Bound Top")
		(29 "B.CrtYd" user "Package Geometry/Place Bound Bottom")
		(35 "F.Fab" user "Ref Des/Assembly Top")
		(33 "B.Fab" user "Ref Des/Assembly Bottom")
	)
	(footprint ""
		(layer "F.Cu")
		(at 352.487738 2.51079 -90)
		(property "Reference" "RT36"
			(at 1.01473 0.656336 180)
			(unlocked yes)
			(layer "F.SilkS")
			(effects
				(font
					(size 0.4064 0.254)
					(thickness 0.1524)
				)
			)
		)
		(property "Value" ""
			(at 0 0 270)
			(layer "F.Fab")
			(effects
				(font
					(size 1.27 1.27)
				)
			)
		)
		(duplicate_pad_numbers_are_jumpers no)
		(fp_poly
			(pts
				(xy -0.4953 -0.2032) (xy 0.4953 -0.2032) (xy 0.4953 1.6002) (xy -0.4953 1.6002)
			)
			(stroke
				(width 0)
				(type default)
			)
			(fill no)
			(layer "F.CrtYd")
		)
		(fp_line
			(start -0.4953 1.6002)
			(end -0.4953 -0.2032)
			(stroke
				(width 0.1)
				(type default)
			)
			(layer "F.Fab")
		)
		(fp_line
			(start 0.4953 1.6002)
			(end -0.4953 1.6002)
			(stroke
				(width 0.1)
				(type default)
			)
			(layer "F.Fab")
		)
		(fp_line
			(start -0.4953 -0.2032)
			(end 0.4953 -0.2032)
			(stroke
				(width 0.1)
				(type default)
			)
			(layer "F.Fab")
		)
		(fp_line
			(start 0.4953 -0.2032)
			(end 0.4953 1.6002)
			(stroke
				(width 0.1)
				(type default)
			)
			(layer "F.Fab")
		)
		(pad "1" smd rect
			(at 0 0 270)
			(size 0.762 0.889)
			(layers "F.Cu" "F.Mask" "F.Paste")
			(net "VR_PVDDQ_ABC_PH2_BOOT")
		)
		(pad "2" smd rect
			(at 0 1.397 270)
			(size 0.762 0.889)
			(layers "F.Cu" "F.Mask" "F.Paste")
			(net "VR_PVDDQ_ABC_PH2_BOOT_R")
		)
		(zone
			(layer "F.Cu")
			(hatch none 0.5)
			(connect_pads
				(clearance 0)
			)
			(min_thickness 0.25)
			(keepout
				(tracks not_allowed)
				(vias allowed)
				(pads allowed)
				(copperpour not_allowed)
				(footprints allowed)
			)
			(placement
				(enabled no)
				(sheetname "")
			)
			(fill
				(thermal_gap 0.5)
				(thermal_bridge_width 0.5)
				(island_removal_mode 0)
			)
			(polygon
				(pts
					(xy 351.535238 2.12979) (xy 351.535238 2.89179) (xy 352.043238 2.89179) (xy 352.043238 2.12979)
				)
			)
		)
		(zone
			(layer "F.Cu")
			(hatch none 0.5)
			(connect_pads
				(clearance 0)
			)
			(min_thickness 0.25)
			(keepout
				(tracks allowed)
				(vias not_allowed)
				(pads allowed)
				(copperpour not_allowed)
				(footprints allowed)
			)
			(placement
				(enabled no)
				(sheetname "")
			)
			(fill
				(thermal_gap 0.5)
				(thermal_bridge_width 0.5)
				(island_removal_mode 0)
			)
			(polygon
				(pts
					(xy 351.535238 2.89179) (xy 352.043238 2.89179) (xy 352.043238 2.12979) (xy 351.535238 2.12979)
				)
			)
		)
	)
	(footprint ""
		(layer "F.Cu")
		(at 483.616 -139.4206)
		(property "Reference" "U6W12"
			(at 0 -1.2065 0)
			(unlocked yes)
			(layer "F.SilkS")
			(effects
				(font
					(size 1.27 0.9652)
					(thickness 0.1524)
				)
				(justify left)
			)
		)
		(property "Value" ""
			(at 0 0 0)
			(layer "F.Fab")
			(effects
				(font
					(size 1.27 1.27)
				)
			)
		)
		(duplicate_pad_numbers_are_jumpers no)
		(fp_circle
			(center -0.848614 -0.6477)
			(end -0.721614 -0.6477)
			(stroke
				(width 0.254)
				(type default)
			)
			(fill no)
			(layer "F.SilkS")
		)
		(fp_poly
			(pts
				(xy 0.21463 -0.450088) (xy 1.56337 -0.450088) (xy 1.56337 1.75006) (xy 0.21463 1.75006)
			)
			(stroke
				(width 0)
				(type default)
			)
			(fill no)
			(layer "F.CrtYd")
		)
		(fp_line
			(start 0.21463 -0.450088)
			(end 1.56337 -0.450088)
			(stroke
				(width 0.1)
				(type default)
			)
			(layer "F.Fab")
		)
		(fp_line
			(start 0.21463 1.75006)
			(end 0.21463 -0.450088)
			(stroke
				(width 0.1)
				(type default)
			)
			(layer "F.Fab")
		)
		(fp_line
			(start 1.56337 -0.450088)
			(end 1.56337 1.75006)
			(stroke
				(width 0.1)
				(type default)
			)
			(layer "F.Fab")
		)
		(fp_line
			(start 1.56337 1.75006)
			(end 0.21463 1.75006)
			(stroke
				(width 0.1)
				(type default)
			)
			(layer "F.Fab")
		)
		(fp_circle
			(center -0.848614 -0.6477)
			(end -0.721614 -0.6477)
			(stroke
				(width 0.254)
				(type default)
			)
			(fill no)
			(layer "F.Fab")
		)
		(pad "1" smd rect
			(at 0 0)
			(size 1.016 0.381)
			(layers "F.Cu" "F.Mask" "F.Paste")
			(net "SPA_MID_DBG2_RX_BUF")
		)
		(pad "2" smd rect
			(at 0 0.649986)
			(size 1.016 0.381)
			(layers "F.Cu" "F.Mask" "F.Paste")
			(net "GND")
		)
		(pad "3" smd rect
			(at 0 1.299972)
			(size 1.016 0.381)
			(layers "F.Cu" "F.Mask" "F.Paste")
			(net "SPA_MID_DBG1_RX")
		)
		(pad "4" smd rect
			(at 1.778 1.299972)
			(size 1.016 0.381)
			(layers "F.Cu" "F.Mask" "F.Paste")
			(net "SPA_MID_DBG_RX")
		)
		(pad "5" smd rect
			(at 1.778 0.649986)
			(size 1.016 0.381)
			(layers "F.Cu" "F.Mask" "F.Paste")
			(net "P3V3_STBY")
		)
		(pad "6" smd rect
			(at 1.778 0)
			(size 1.016 0.381)
			(layers "F.Cu" "F.Mask" "F.Paste")
			(net "DEBUG_CARD2_PRSNT")
		)
	)
	(footprint ""
		(layer "F.Cu")
		(at 185.3184 -138.2141)
		(property "Reference" "FB4A1"
			(at 0 0 0)
			(layer "F.SilkS")
			(hide yes)
			(effects
				(font
					(size 1.27 1.27)
				)
			)
		)
		(property "Value" ""
			(at 0 0 0)
			(layer "F.Fab")
			(effects
				(font
					(size 1.27 1.27)
				)
			)
		)
		(duplicate_pad_numbers_are_jumpers no)
		(fp_poly
			(pts
				(xy -0.7239 -0.26035) (xy 0.7239 -0.26035) (xy 0.7239 2.03835) (xy -0.7239 2.03835)
			)
			(stroke
				(width 0)
				(type default)
			)
			(fill no)
			(layer "F.CrtYd")
		)
		(fp_line
			(start -0.7239 -0.26035)
			(end 0.7239 -0.26035)
			(stroke
				(width 0.1)
				(type default)
			)
			(layer "F.Fab")
		)
		(fp_line
			(start -0.7239 2.03835)
			(end -0.7239 -0.26035)
			(stroke
				(width 0.1)
				(type default)
			)
			(layer "F.Fab")
		)
		(fp_line
			(start 0.7239 -0.26035)
			(end 0.7239 2.03835)
			(stroke
				(width 0.1)
				(type default)
			)
			(layer "F.Fab")
		)
		(fp_line
			(start 0.7239 2.03835)
			(end -0.7239 2.03835)
			(stroke
				(width 0.1)
				(type default)
			)
			(layer "F.Fab")
		)
		(pad "1" smd rect
			(at 0 0)
			(size 1.27 1.016)
			(layers "F.Cu" "F.Mask" "F.Paste")
			(net "P12V_STBY")
		)
		(pad "2" smd rect
			(at 0 1.778)
			(size 1.27 1.016)
			(layers "F.Cu" "F.Mask" "F.Paste")
			(net "VR_FET_SW_P12V_STBY_PVPP_KLM")
		)
		(zone
			(layer "F.Cu")
			(hatch none 0.5)
			(connect_pads
				(clearance 0)
			)
			(min_thickness 0.25)
			(keepout
				(tracks not_allowed)
				(vias allowed)
				(pads allowed)
				(copperpour not_allowed)
				(footprints allowed)
			)
			(placement
				(enabled no)
				(sheetname "")
			)
			(fill
				(thermal_gap 0.5)
				(thermal_bridge_width 0.5)
				(island_removal_mode 0)
			)
			(polygon
				(pts
					(xy 185.9534 -137.7061) (xy 185.9534 -136.9441) (xy 185.8645 -136.9441) (xy 184.6834 -136.9441)
					(xy 184.6834 -137.7061)
				)
			)
		)
	)
	(footprint ""
		(layer "F.Cu")
		(at 109.638592 -77.429614)
		(property "Reference" "C3D12"
			(at 0 0 0)
			(layer "F.SilkS")
			(hide yes)
			(effects
				(font
					(size 1.27 1.27)
				)
			)
		)
		(property "Value" ""
			(at 0 0 0)
			(layer "F.Fab")
			(effects
				(font
					(size 1.27 1.27)
				)
			)
		)
		(duplicate_pad_numbers_are_jumpers no)
		(fp_poly
			(pts
				(xy -0.4953 -0.2032) (xy 0.4953 -0.2032) (xy 0.4953 1.6002) (xy -0.4953 1.6002)
			)
			(stroke
				(width 0)
				(type default)
			)
			(fill no)
			(layer "F.CrtYd")
		)
		(fp_line
			(start -0.4953 -0.2032)
			(end 0.4953 -0.2032)
			(stroke
				(width 0.1)
				(type default)
			)
			(layer "F.Fab")
		)
		(fp_line
			(start -0.4953 1.6002)
			(end -0.4953 -0.2032)
			(stroke
				(width 0.1)
				(type default)
			)
			(layer "F.Fab")
		)
		(fp_line
			(start 0.4953 -0.2032)
			(end 0.4953 1.6002)
			(stroke
				(width 0.1)
				(type default)
			)
			(layer "F.Fab")
		)
		(fp_line
			(start 0.4953 1.6002)
			(end -0.4953 1.6002)
			(stroke
				(width 0.1)
				(type default)
			)
			(layer "F.Fab")
		)
		(pad "1" smd rect
			(at 0 0)
			(size 0.762 0.889)
			(layers "F.Cu" "F.Mask" "F.Paste")
			(net "PVCCMCP_CPU1")
		)
		(pad "2" smd rect
			(at 0 1.397)
			(size 0.762 0.889)
			(layers "F.Cu" "F.Mask" "F.Paste")
			(net "GND")
		)
		(zone
			(layer "F.Cu")
			(hatch none 0.5)
			(connect_pads
				(clearance 0)
			)
			(min_thickness 0.25)
			(keepout
				(tracks not_allowed)
				(vias allowed)
				(pads allowed)
				(copperpour not_allowed)
				(footprints allowed)
			)
			(placement
				(enabled no)
				(sheetname "")
			)
			(fill
				(thermal_gap 0.5)
				(thermal_bridge_width 0.5)
				(island_removal_mode 0)
			)
			(polygon
				(pts
					(xy 109.257592 -76.985114) (xy 110.019592 -76.985114) (xy 110.019592 -76.477114) (xy 109.257592 -76.477114)
				)
			)
		)
	)
	(footprint ""
		(layer "F.Cu")
		(at 184.147968 -134.173722 90)
		(property "Reference" "C4B1"
			(at 0 0 90)
			(layer "F.SilkS")
			(hide yes)
			(effects
				(font
					(size 1.27 1.27)
				)
			)
		)
		(property "Value" "*"
			(at -0.0762 -6.2357 90)
			(unlocked yes)
			(layer "F.Fab")
			(hide yes)
			(effects
				(font
					(size 1.27 1.016)
					(thickness 0.1524)
				)
			)
		)
		(property "Device Type" "SC22U16V5MX-4-GP_SMD-BCG5-SC22A"
			(at -0.0762 -8.2677 90)
			(unlocked yes)
			(layer "F.Fab")
			(hide yes)
			(effects
				(font
					(size 1.27 1.016)
					(thickness 0.1524)
				)
			)
		)
		(duplicate_pad_numbers_are_jumpers no)
		(fp_line
			(start 0.635 0)
			(end -0.635 0)
			(stroke
				(width 0.508)
				(type default)
			)
			(layer "F.SilkS")
		)
		(fp_rect
			(start -0.9652 1.778)
			(end 0.9652 -1.778)
			(stroke
				(width 0)
				(type default)
			)
			(fill no)
			(layer "F.CrtYd")
		)
		(fp_poly
			(pts
				(xy -0.9652 -1.778) (xy 0.9652 -1.778) (xy 0.9652 1.778) (xy -0.9652 1.778)
			)
			(stroke
				(width 0)
				(type default)
			)
			(fill no)
			(layer "F.Fab")
		)
		(pad "1" smd rect
			(at 0 -0.9652 90)
			(size 1.397 1.143)
			(layers "F.Cu" "F.Mask" "F.Paste")
			(net "VR_FET_SW_P12V_STBY_PVPP_KLM")
		)
		(pad "2" smd rect
			(at 0 0.9652 90)
			(size 1.397 1.143)
			(layers "F.Cu" "F.Mask" "F.Paste")
			(net "GND")
		)
	)
	(footprint ""
		(layer "F.Cu")
		(at 13.941806 3.507232 90)
		(property "Reference" "C1G23"
			(at 0 0 90)
			(layer "F.SilkS")
			(hide yes)
			(effects
				(font
					(size 1.27 1.27)
				)
			)
		)
		(property "Value" ""
			(at 0 0 90)
			(layer "F.Fab")
			(effects
				(font
					(size 1.27 1.27)
				)
			)
		)
		(duplicate_pad_numbers_are_jumpers no)
		(fp_poly
			(pts
				(xy 0.3048 -0.1016) (xy 0.3048 0.9906) (xy -0.3048 0.9906) (xy -0.3048 -0.1016)
			)
			(stroke
				(width 0)
				(type default)
			)
			(fill no)
			(layer "F.CrtYd")
		)
		(fp_line
			(start 0.3048 -0.1016)
			(end -0.3048 -0.1016)
			(stroke
				(width 0.1)
				(type default)
			)
			(layer "F.Fab")
		)
		(fp_line
			(start -0.3048 -0.1016)
			(end -0.3048 0.9906)
			(stroke
				(width 0.1)
				(type default)
			)
			(layer "F.Fab")
		)
		(fp_line
			(start 0.3048 0.9906)
			(end 0.3048 -0.1016)
			(stroke
				(width 0.1)
				(type default)
			)
			(layer "F.Fab")
		)
		(fp_line
			(start -0.3048 0.9906)
			(end 0.3048 0.9906)
			(stroke
				(width 0.1)
				(type default)
			)
			(layer "F.Fab")
		)
		(pad "1" smd rect
			(at 0 0 90)
			(size 0.508 0.508)
			(layers "F.Cu" "F.Mask" "F.Paste")
			(net "VR_PVDDQ_GHJ_VD12")
		)
		(pad "2" smd rect
			(at 0 0.889 90)
			(size 0.508 0.508)
			(layers "F.Cu" "F.Mask" "F.Paste")
			(net "GND")
		)
		(zone
			(layer "F.Cu")
			(hatch none 0.5)
			(connect_pads
				(clearance 0)
			)
			(min_thickness 0.25)
			(keepout
				(tracks allowed)
				(vias not_allowed)
				(pads allowed)
				(copperpour not_allowed)
				(footprints allowed)
			)
			(placement
				(enabled no)
				(sheetname "")
			)
			(fill
				(thermal_gap 0.5)
				(thermal_bridge_width 0.5)
				(island_removal_mode 0)
			)
			(polygon
				(pts
					(xy 14.195806 3.761232) (xy 14.195806 3.253232) (xy 14.576806 3.253232) (xy 14.576806 3.761232)
				)
			)
		)
		(zone
			(layer "F.Cu")
			(hatch none 0.5)
			(connect_pads
				(clearance 0)
			)
			(min_thickness 0.25)
			(keepout
				(tracks not_allowed)
				(vias allowed)
				(pads allowed)
				(copperpour not_allowed)
				(footprints allowed)
			)
			(placement
				(enabled no)
				(sheetname "")
			)
			(fill
				(thermal_gap 0.5)
				(thermal_bridge_width 0.5)
				(island_removal_mode 0)
			)
			(polygon
				(pts
					(xy 14.576806 3.761232) (xy 14.576806 3.253232) (xy 14.195806 3.253232) (xy 14.195806 3.761232)
				)
			)
		)
	)
	(footprint ""
		(layer "F.Cu")
		(at 33.2105 -76.708 90)
		(property "Reference" "C1D28"
			(at 0 0 90)
			(layer "F.SilkS")
			(hide yes)
			(effects
				(font
					(size 1.27 1.27)
				)
			)
		)
		(property "Value" ""
			(at 0 0 90)
			(layer "F.Fab")
			(effects
				(font
					(size 1.27 1.27)
				)
			)
		)
		(duplicate_pad_numbers_are_jumpers no)
		(fp_rect
			(start 0.3048 0.9906)
			(end -0.3048 -0.1016)
			(stroke
				(width 0)
				(type default)
			)
			(fill no)
			(layer "F.CrtYd")
		)
		(fp_line
			(start 0.3048 -0.1016)
			(end -0.3048 -0.1016)
			(stroke
				(width 0.1)
				(type default)
			)
			(layer "F.Fab")
		)
		(fp_line
			(start -0.3048 -0.1016)
			(end -0.3048 0.9906)
			(stroke
				(width 0.1)
				(type default)
			)
			(layer "F.Fab")
		)
		(fp_line
			(start 0.3048 0.9906)
			(end 0.3048 -0.1016)
			(stroke
				(width 0.1)
				(type default)
			)
			(layer "F.Fab")
		)
		(fp_line
			(start -0.3048 0.9906)
			(end 0.3048 0.9906)
			(stroke
				(width 0.1)
				(type default)
			)
			(layer "F.Fab")
		)
		(pad "1" smd rect
			(at 0 0 90)
			(size 0.508 0.508)
			(layers "F.Cu" "F.Mask" "F.Paste")
			(net "VR_FET_SW_P12V_STBY_PVCCIN_CPU1")
		)
		(pad "2" smd rect
			(at 0 0.889 90)
			(size 0.508 0.508)
			(layers "F.Cu" "F.Mask" "F.Paste")
			(net "GND")
		)
		(zone
			(layer "F.Cu")
			(hatch none 0.5)
			(connect_pads
				(clearance 0)
			)
			(min_thickness 0.25)
			(keepout
				(tracks not_allowed)
				(vias allowed)
				(pads allowed)
				(copperpour not_allowed)
				(footprints allowed)
			)
			(placement
				(enabled no)
				(sheetname "")
			)
			(fill
				(thermal_gap 0.5)
				(thermal_bridge_width 0.5)
				(island_removal_mode 0)
			)
			(polygon
				(pts
					(xy 33.8455 -76.962) (xy 33.4645 -76.962) (xy 33.4645 -76.454) (xy 33.8455 -76.454)
				)
			)
		)
		(zone
			(layer "F.Cu")
			(hatch none 0.5)
			(connect_pads
				(clearance 0)
			)
			(min_thickness 0.25)
			(keepout
				(tracks allowed)
				(vias not_allowed)
				(pads allowed)
				(copperpour not_allowed)
				(footprints allowed)
			)
			(placement
				(enabled no)
				(sheetname "")
			)
			(fill
				(thermal_gap 0.5)
				(thermal_bridge_width 0.5)
				(island_removal_mode 0)
			)
			(polygon
				(pts
					(xy 33.8455 -76.962) (xy 33.4645 -76.962) (xy 33.4645 -76.454) (xy 33.8455 -76.454)
				)
			)
		)
	)
	(footprint ""
		(layer "F.Cu")
		(at 27.559 -65.913 90)
		(property "Reference" "RT17"
			(at 1.01473 0.656336 0)
			(unlocked yes)
			(layer "F.SilkS")
			(effects
				(font
					(size 0.4064 0.254)
					(thickness 0.1524)
				)
			)
		)
		(property "Value" ""
			(at 0 0 90)
			(layer "F.Fab")
			(effects
				(font
					(size 1.27 1.27)
				)
			)
		)
		(duplicate_pad_numbers_are_jumpers no)
		(fp_poly
			(pts
				(xy -0.4953 -0.2032) (xy 0.4953 -0.2032) (xy 0.4953 1.6002) (xy -0.4953 1.6002)
			)
			(stroke
				(width 0)
				(type default)
			)
			(fill no)
			(layer "F.CrtYd")
		)
		(fp_line
			(start 0.4953 -0.2032)
			(end 0.4953 1.6002)
			(stroke
				(width 0.1)
				(type default)
			)
			(layer "F.Fab")
		)
		(fp_line
			(start -0.4953 -0.2032)
			(end 0.4953 -0.2032)
			(stroke
				(width 0.1)
				(type default)
			)
			(layer "F.Fab")
		)
		(fp_line
			(start 0.4953 1.6002)
			(end -0.4953 1.6002)
			(stroke
				(width 0.1)
				(type default)
			)
			(layer "F.Fab")
		)
		(fp_line
			(start -0.4953 1.6002)
			(end -0.4953 -0.2032)
			(stroke
				(width 0.1)
				(type default)
			)
			(layer "F.Fab")
		)
		(pad "1" smd rect
			(at 0 0 90)
			(size 0.762 0.889)
			(layers "F.Cu" "F.Mask" "F.Paste")
			(net "VR_PVCCIN_CPU1_PH2_BOOT")
		)
		(pad "2" smd rect
			(at 0 1.397 90)
			(size 0.762 0.889)
			(layers "F.Cu" "F.Mask" "F.Paste")
			(net "VR_PVCCIN_CPU1_PH2_BOOT_R")
		)
		(zone
			(layer "F.Cu")
			(hatch none 0.5)
			(connect_pads
				(clearance 0)
			)
			(min_thickness 0.25)
			(keepout
				(tracks allowed)
				(vias not_allowed)
				(pads allowed)
				(copperpour not_allowed)
				(footprints allowed)
			)
			(placement
				(enabled no)
				(sheetname "")
			)
			(fill
				(thermal_gap 0.5)
				(thermal_bridge_width 0.5)
				(island_removal_mode 0)
			)
			(polygon
				(pts
					(xy 28.5115 -66.294) (xy 28.0035 -66.294) (xy 28.0035 -65.532) (xy 28.5115 -65.532)
				)
			)
		)
		(zone
			(layer "F.Cu")
			(hatch none 0.5)
			(connect_pads
				(clearance 0)
			)
			(min_thickness 0.25)
			(keepout
				(tracks not_allowed)
				(vias allowed)
				(pads allowed)
				(copperpour not_allowed)
				(footprints allowed)
			)
			(placement
				(enabled no)
				(sheetname "")
			)
			(fill
				(thermal_gap 0.5)
				(thermal_bridge_width 0.5)
				(island_removal_mode 0)
			)
			(polygon
				(pts
					(xy 28.5115 -65.532) (xy 28.5115 -66.294) (xy 28.0035 -66.294) (xy 28.0035 -65.532)
				)
			)
		)
	)
)
